(kicad_pcb
	(version 20260206)
	(generator "pcbnew")
	(generator_version "10.0")
	(general
		(thickness 1.6)
		(legacy_teardrops no)
	)
	(paper "A4")
	(title_block
		(title "Bryce Canyon_R.DPB_16317-1_OCP.brd")
		(comment 1 "Bryce Canyon / footprints 148-155 of 2099")
	)
	(layers
		(0 "F.Cu" signal "TOP")
		(4 "In1.Cu" signal "L2GND")
		(6 "In2.Cu" signal "L3")
		(8 "In3.Cu" signal "L4VCC")
		(10 "In4.Cu" signal "L5VCC")
		(12 "In5.Cu" signal "L6")
		(14 "In6.Cu" signal "L7GND")
		(2 "B.Cu" signal "BOTTOM")
		(9 "F.Adhes" user "F.Adhesive")
		(11 "B.Adhes" user "B.Adhesive")
		(13 "F.Paste" user "Package Geometry/Pastemask Top")
		(15 "B.Paste" user "Package Geometry/Pastemask Bottom")
		(5 "F.SilkS" user "Ref Des/Silkscreen Top")
		(7 "B.SilkS" user "Ref Des/Silkscreen Bottom")
		(1 "F.Mask" user "Board Geometry/Soldermask Top")
		(3 "B.Mask" user "Board Geometry/Soldermask Bottom")
		(17 "Dwgs.User" user "User.Drawings")
		(19 "Cmts.User" user "User.Comments")
		(21 "Eco1.User" user "User.Eco1")
		(23 "Eco2.User" user "User.Eco2")
		(25 "Edge.Cuts" user "Board Geometry/Outline")
		(27 "Margin" user)
		(31 "F.CrtYd" user "Package Geometry/Place Bound Top")
		(29 "B.CrtYd" user "Package Geometry/Place Bound Bottom")
		(35 "F.Fab" user "Ref Des/Assembly Top")
		(33 "B.Fab" user "Ref Des/Assembly Bottom")
	)
	(footprint ""
		(layer "F.Cu")
		(at 111.506 -132.588 180)
		(property "Reference" "D15"
			(at 0 0 180)
			(layer "F.SilkS")
			(hide yes)
			(effects
				(font
					(size 1.27 1.27)
				)
			)
		)
		(property "Value" "RB551V30-GP"
			(at 0 -6.7818 180)
			(unlocked yes)
			(layer "F.Fab")
			(hide yes)
			(effects
				(font
					(size 1.016 1.016)
					(thickness 0.1524)
				)
			)
		)
		(property "Device Type" "SOD323AKH38"
			(at 0 -8.6868 180)
			(unlocked yes)
			(layer "F.Fab")
			(hide yes)
			(effects
				(font
					(size 1.016 1.016)
					(thickness 0.1524)
				)
			)
		)
		(duplicate_pad_numbers_are_jumpers no)
		(fp_line
			(start 0.889 2.159)
			(end -0.889 2.159)
			(stroke
				(width 0.1524)
				(type default)
			)
			(layer "F.SilkS")
		)
		(fp_line
			(start 0.889 -1.9304)
			(end 0.889 2.159)
			(stroke
				(width 0.1524)
				(type default)
			)
			(layer "F.SilkS")
		)
		(fp_line
			(start 0.762 2.0574)
			(end -0.762 2.0574)
			(stroke
				(width 0.508)
				(type default)
			)
			(layer "F.SilkS")
		)
		(fp_line
			(start -0.889 2.159)
			(end -0.889 -1.9304)
			(stroke
				(width 0.1524)
				(type default)
			)
			(layer "F.SilkS")
		)
		(fp_line
			(start -0.889 -1.9304)
			(end 0.889 -1.9304)
			(stroke
				(width 0.1524)
				(type default)
			)
			(layer "F.SilkS")
		)
		(fp_rect
			(start -1.016 2.3114)
			(end 1.016 -2.0066)
			(stroke
				(width 0)
				(type default)
			)
			(fill no)
			(layer "F.CrtYd")
		)
		(fp_poly
			(pts
				(xy -1.016 -2.0066) (xy 1.016 -2.0066) (xy 1.016 2.3114) (xy -1.016 2.3114)
			)
			(stroke
				(width 0)
				(type default)
			)
			(fill no)
			(layer "F.Fab")
		)
		(pad "A" smd rect
			(at 0 -1.143 180)
			(size 0.5588 1.016)
			(layers "F.Cu" "F.Mask" "F.Paste")
			(net "SW_HDD_R15")
		)
		(pad "K" smd rect
			(at 0 1.143 180)
			(size 0.5588 1.016)
			(layers "F.Cu" "F.Mask" "F.Paste")
			(net "SW_HDD_N15")
		)
	)
	(footprint ""
		(layer "F.Cu")
		(at 129.413762 -39.705026)
		(property "Reference" "TP156"
			(at 0 0 0)
			(layer "F.SilkS")
			(hide yes)
			(effects
				(font
					(size 1.27 1.27)
				)
			)
		)
		(property "Value" "*"
			(at -0.0508 -1.6764 0)
			(unlocked yes)
			(layer "F.Fab")
			(hide yes)
			(effects
				(font
					(size 1.016 1.016)
					(thickness 0.1524)
				)
			)
		)
		(property "Device Type" "TPAD32"
			(at -0.0508 -3.2004 0)
			(unlocked yes)
			(layer "F.Fab")
			(hide yes)
			(effects
				(font
					(size 1.016 1.016)
					(thickness 0.1524)
				)
			)
		)
		(duplicate_pad_numbers_are_jumpers no)
		(fp_poly
			(pts
				(arc
					(start 0.4064 0)
					(mid -0.4064 0)
					(end 0.4064 0)
				)
			)
			(stroke
				(width 0)
				(type default)
			)
			(fill no)
			(layer "F.CrtYd")
		)
		(fp_poly
			(pts
				(arc
					(start 0.7112 0)
					(mid -0.7112 0)
					(end 0.7112 0)
				)
			)
			(stroke
				(width 0)
				(type default)
			)
			(fill no)
			(layer "F.Fab")
		)
		(pad "1" smd circle
			(at 0 0)
			(size 0.8128 0.8128)
			(layers "F.Cu" "F.Mask" "F.Paste")
			(net "ACT_HDD_27")
		)
	)
	(footprint ""
		(layer "F.Cu")
		(at 149.987 -263.271)
		(property "Reference" "R222"
			(at 0 0 0)
			(layer "F.SilkS")
			(hide yes)
			(effects
				(font
					(size 1.27 1.27)
				)
			)
		)
		(property "Value" "2R6F-GP"
			(at -0.0508 -4.8514 0)
			(unlocked yes)
			(layer "F.Fab")
			(hide yes)
			(effects
				(font
					(size 1.016 1.016)
					(thickness 0.1524)
				)
			)
		)
		(property "Device Type" "R1206H26"
			(at 0 -6.3754 0)
			(unlocked yes)
			(layer "F.Fab")
			(hide yes)
			(effects
				(font
					(size 1.016 1.016)
					(thickness 0.1524)
				)
			)
		)
		(duplicate_pad_numbers_are_jumpers no)
		(fp_line
			(start -1.016 -2.2352)
			(end 1.016 -2.2352)
			(stroke
				(width 0.1524)
				(type default)
			)
			(layer "F.SilkS")
		)
		(fp_line
			(start -1.016 2.2352)
			(end -1.016 -2.2352)
			(stroke
				(width 0.1524)
				(type default)
			)
			(layer "F.SilkS")
		)
		(fp_line
			(start 1.016 -2.2352)
			(end 1.016 2.2352)
			(stroke
				(width 0.1524)
				(type default)
			)
			(layer "F.SilkS")
		)
		(fp_line
			(start 1.016 2.2352)
			(end -1.016 2.2352)
			(stroke
				(width 0.1524)
				(type default)
			)
			(layer "F.SilkS")
		)
		(fp_rect
			(start -1.0922 2.3114)
			(end 1.0922 -2.3114)
			(stroke
				(width 0)
				(type default)
			)
			(fill no)
			(layer "F.CrtYd")
		)
		(fp_poly
			(pts
				(xy -1.0922 -2.3114) (xy 1.0922 -2.3114) (xy 1.0922 2.3114) (xy -1.0922 2.3114)
			)
			(stroke
				(width 0)
				(type default)
			)
			(fill no)
			(layer "F.Fab")
		)
		(pad "1" smd rect
			(at 0 -1.397)
			(size 1.651 1.27)
			(layers "F.Cu" "F.Mask" "F.Paste")
			(net "P5V_HDD4")
		)
		(pad "2" smd rect
			(at 0 1.397)
			(size 1.651 1.27)
			(layers "F.Cu" "F.Mask" "F.Paste")
			(net "5V_PRE_4")
		)
	)
	(footprint ""
		(layer "F.Cu")
		(at 181.61 -365.379 90)
		(property "Reference" "R986"
			(at 0 0 90)
			(layer "F.SilkS")
			(hide yes)
			(effects
				(font
					(size 1.27 1.27)
				)
			)
		)
		(property "Value" "0R2J-2-GP"
			(at 0.064008 -3.993896 90)
			(unlocked yes)
			(layer "F.Fab")
			(hide yes)
			(effects
				(font
					(size 1.016 1.016)
					(thickness 0.1524)
				)
			)
		)
		(property "Device Type" "R402H16"
			(at 0.064008 -5.517896 90)
			(unlocked yes)
			(layer "F.Fab")
			(hide yes)
			(effects
				(font
					(size 1.016 1.016)
					(thickness 0.1524)
				)
			)
		)
		(duplicate_pad_numbers_are_jumpers no)
		(fp_line
			(start 0.508 -0.9398)
			(end -0.508 -0.9398)
			(stroke
				(width 0.1524)
				(type default)
			)
			(layer "F.SilkS")
		)
		(fp_line
			(start -0.508 -0.9398)
			(end -0.508 0.9398)
			(stroke
				(width 0.1524)
				(type default)
			)
			(layer "F.SilkS")
		)
		(fp_rect
			(start -0.508 0.9398)
			(end 0.508 -0.9398)
			(stroke
				(width 0)
				(type default)
			)
			(fill no)
			(layer "F.CrtYd")
		)
		(fp_rect
			(start -0.508 0.9398)
			(end 0.508 -0.9398)
			(stroke
				(width 0)
				(type default)
			)
			(fill no)
			(layer "F.Fab")
		)
		(pad "1" smd custom
			(at 0 -0.4445 90)
			(size 0.1397 0.1397)
			(layers "F.Cu" "F.Mask" "F.Paste")
			(net "MB0_CM_ADR2_R")
			(options
				(clearance outline)
				(anchor circle)
			)
			(primitives
				(gr_poly
					(pts
						(arc
							(start -0.1778 -0.2794)
							(mid -0.249642 -0.249642)
							(end -0.2794 -0.1778)
						)
						(arc
							(start -0.2794 0.1778)
							(mid -0.249642 0.249642)
							(end -0.1778 0.2794)
						)
						(arc
							(start 0.1778 0.2794)
							(mid 0.249642 0.249642)
							(end 0.2794 0.1778)
						)
						(arc
							(start 0.2794 -0.1778)
							(mid 0.249642 -0.249642)
							(end 0.1778 -0.2794)
						)
					)
					(width 0)
					(fill yes)
				)
			)
		)
		(pad "2" smd custom
			(at 0 0.4445 90)
			(size 0.1397 0.1397)
			(layers "F.Cu" "F.Mask" "F.Paste")
			(net "AGND_CURRENT_MON")
			(options
				(clearance outline)
				(anchor circle)
			)
			(primitives
				(gr_poly
					(pts
						(arc
							(start -0.1778 -0.2794)
							(mid -0.249642 -0.249642)
							(end -0.2794 -0.1778)
						)
						(arc
							(start -0.2794 0.1778)
							(mid -0.249642 0.249642)
							(end -0.1778 0.2794)
						)
						(arc
							(start 0.1778 0.2794)
							(mid 0.249642 0.249642)
							(end 0.2794 0.1778)
						)
						(arc
							(start 0.2794 -0.1778)
							(mid 0.249642 -0.249642)
							(end 0.1778 -0.2794)
						)
					)
					(width 0)
					(fill yes)
				)
			)
		)
	)
	(footprint ""
		(layer "F.Cu")
		(at 46.482 -246.634 90)
		(property "Reference" "R184"
			(at 0 0 90)
			(layer "F.SilkS")
			(hide yes)
			(effects
				(font
					(size 1.27 1.27)
				)
			)
		)
		(property "Value" "4K7R2J-2-GP"
			(at 0.064008 -3.993896 90)
			(unlocked yes)
			(layer "F.Fab")
			(hide yes)
			(effects
				(font
					(size 1.016 1.016)
					(thickness 0.1524)
				)
			)
		)
		(property "Device Type" "R402H16"
			(at 0.064008 -5.517896 90)
			(unlocked yes)
			(layer "F.Fab")
			(hide yes)
			(effects
				(font
					(size 1.016 1.016)
					(thickness 0.1524)
				)
			)
		)
		(duplicate_pad_numbers_are_jumpers no)
		(fp_line
			(start 0.508 -0.9398)
			(end -0.508 -0.9398)
			(stroke
				(width 0.1524)
				(type default)
			)
			(layer "F.SilkS")
		)
		(fp_line
			(start -0.508 -0.9398)
			(end -0.508 0.9398)
			(stroke
				(width 0.1524)
				(type default)
			)
			(layer "F.SilkS")
		)
		(fp_rect
			(start -0.508 0.9398)
			(end 0.508 -0.9398)
			(stroke
				(width 0)
				(type default)
			)
			(fill no)
			(layer "F.CrtYd")
		)
		(fp_rect
			(start -0.508 0.9398)
			(end 0.508 -0.9398)
			(stroke
				(width 0)
				(type default)
			)
			(fill no)
			(layer "F.Fab")
		)
		(pad "1" smd custom
			(at 0 -0.4445 90)
			(size 0.1397 0.1397)
			(layers "F.Cu" "F.Mask" "F.Paste")
			(net "P12V_B")
			(options
				(clearance outline)
				(anchor circle)
			)
			(primitives
				(gr_poly
					(pts
						(arc
							(start -0.1778 -0.2794)
							(mid -0.249642 -0.249642)
							(end -0.2794 -0.1778)
						)
						(arc
							(start -0.2794 0.1778)
							(mid -0.249642 0.249642)
							(end -0.1778 0.2794)
						)
						(arc
							(start 0.1778 0.2794)
							(mid 0.249642 0.249642)
							(end 0.2794 0.1778)
						)
						(arc
							(start 0.2794 -0.1778)
							(mid 0.249642 -0.249642)
							(end 0.1778 -0.2794)
						)
					)
					(width 0)
					(fill yes)
				)
			)
		)
		(pad "2" smd custom
			(at 0 0.4445 90)
			(size 0.1397 0.1397)
			(layers "F.Cu" "F.Mask" "F.Paste")
			(net "SW_HDD_R1")
			(options
				(clearance outline)
				(anchor circle)
			)
			(primitives
				(gr_poly
					(pts
						(arc
							(start -0.1778 -0.2794)
							(mid -0.249642 -0.249642)
							(end -0.2794 -0.1778)
						)
						(arc
							(start -0.2794 0.1778)
							(mid -0.249642 0.249642)
							(end -0.1778 0.2794)
						)
						(arc
							(start 0.1778 0.2794)
							(mid 0.249642 0.249642)
							(end 0.2794 0.1778)
						)
						(arc
							(start 0.2794 -0.1778)
							(mid 0.249642 -0.249642)
							(end 0.1778 -0.2794)
						)
					)
					(width 0)
					(fill yes)
				)
			)
		)
	)
	(footprint ""
		(layer "F.Cu")
		(at 244.729 -311.912)
		(property "Reference" "R1095"
			(at 0 0 0)
			(layer "F.SilkS")
			(hide yes)
			(effects
				(font
					(size 1.27 1.27)
				)
			)
		)
		(property "Value" "0R2J-2-GP"
			(at 0.064008 -3.993896 0)
			(unlocked yes)
			(layer "F.Fab")
			(hide yes)
			(effects
				(font
					(size 1.016 1.016)
					(thickness 0.1524)
				)
			)
		)
		(property "Device Type" "R402H16"
			(at 0.064008 -5.517896 0)
			(unlocked yes)
			(layer "F.Fab")
			(hide yes)
			(effects
				(font
					(size 1.016 1.016)
					(thickness 0.1524)
				)
			)
		)
		(duplicate_pad_numbers_are_jumpers no)
		(fp_line
			(start -0.508 -0.9398)
			(end -0.508 0.9398)
			(stroke
				(width 0.1524)
				(type default)
			)
			(layer "F.SilkS")
		)
		(fp_line
			(start 0.508 -0.9398)
			(end -0.508 -0.9398)
			(stroke
				(width 0.1524)
				(type default)
			)
			(layer "F.SilkS")
		)
		(fp_rect
			(start -0.508 0.9398)
			(end 0.508 -0.9398)
			(stroke
				(width 0)
				(type default)
			)
			(fill no)
			(layer "F.CrtYd")
		)
		(fp_rect
			(start -0.508 0.9398)
			(end 0.508 -0.9398)
			(stroke
				(width 0)
				(type default)
			)
			(fill no)
			(layer "F.Fab")
		)
		(pad "1" smd custom
			(at 0 -0.4445)
			(size 0.1397 0.1397)
			(layers "F.Cu" "F.Mask" "F.Paste")
			(net "GND")
			(options
				(clearance outline)
				(anchor circle)
			)
			(primitives
				(gr_poly
					(pts
						(arc
							(start -0.1778 -0.2794)
							(mid -0.249642 -0.249642)
							(end -0.2794 -0.1778)
						)
						(arc
							(start -0.2794 0.1778)
							(mid -0.249642 0.249642)
							(end -0.1778 0.2794)
						)
						(arc
							(start 0.1778 0.2794)
							(mid 0.249642 0.249642)
							(end 0.2794 0.1778)
						)
						(arc
							(start 0.2794 -0.1778)
							(mid 0.249642 -0.249642)
							(end 0.1778 -0.2794)
						)
					)
					(width 0)
					(fill yes)
				)
			)
		)
		(pad "2" smd custom
			(at 0 0.4445)
			(size 0.1397 0.1397)
			(layers "F.Cu" "F.Mask" "F.Paste")
			(net "MAX31790_A_SPIN_ST")
			(options
				(clearance outline)
				(anchor circle)
			)
			(primitives
				(gr_poly
					(pts
						(arc
							(start -0.1778 -0.2794)
							(mid -0.249642 -0.249642)
							(end -0.2794 -0.1778)
						)
						(arc
							(start -0.2794 0.1778)
							(mid -0.249642 0.249642)
							(end -0.1778 0.2794)
						)
						(arc
							(start 0.1778 0.2794)
							(mid 0.249642 0.249642)
							(end 0.2794 0.1778)
						)
						(arc
							(start 0.2794 -0.1778)
							(mid 0.249642 -0.249642)
							(end 0.1778 -0.2794)
						)
					)
					(width 0)
					(fill yes)
				)
			)
		)
	)
	(footprint ""
		(layer "F.Cu")
		(at 149.225 -249.555 90)
		(property "Reference" "R231"
			(at 0 0 90)
			(layer "F.SilkS")
			(hide yes)
			(effects
				(font
					(size 1.27 1.27)
				)
			)
		)
		(property "Value" "4K7R2F-GP"
			(at 0.064008 -3.993896 90)
			(unlocked yes)
			(layer "F.Fab")
			(hide yes)
			(effects
				(font
					(size 1.016 1.016)
					(thickness 0.1524)
				)
			)
		)
		(property "Device Type" "R402H16"
			(at 0.064008 -5.517896 90)
			(unlocked yes)
			(layer "F.Fab")
			(hide yes)
			(effects
				(font
					(size 1.016 1.016)
					(thickness 0.1524)
				)
			)
		)
		(duplicate_pad_numbers_are_jumpers no)
		(fp_line
			(start 0.508 -0.9398)
			(end -0.508 -0.9398)
			(stroke
				(width 0.1524)
				(type default)
			)
			(layer "F.SilkS")
		)
		(fp_line
			(start -0.508 -0.9398)
			(end -0.508 0.9398)
			(stroke
				(width 0.1524)
				(type default)
			)
			(layer "F.SilkS")
		)
		(fp_rect
			(start -0.508 0.9398)
			(end 0.508 -0.9398)
			(stroke
				(width 0)
				(type default)
			)
			(fill no)
			(layer "F.CrtYd")
		)
		(fp_rect
			(start -0.508 0.9398)
			(end 0.508 -0.9398)
			(stroke
				(width 0)
				(type default)
			)
			(fill no)
			(layer "F.Fab")
		)
		(pad "1" smd custom
			(at 0 -0.4445 90)
			(size 0.1397 0.1397)
			(layers "F.Cu" "F.Mask" "F.Paste")
			(net "SW_PWR_R_HDD4")
			(options
				(clearance outline)
				(anchor circle)
			)
			(primitives
				(gr_poly
					(pts
						(arc
							(start -0.1778 -0.2794)
							(mid -0.249642 -0.249642)
							(end -0.2794 -0.1778)
						)
						(arc
							(start -0.2794 0.1778)
							(mid -0.249642 0.249642)
							(end -0.1778 0.2794)
						)
						(arc
							(start 0.1778 0.2794)
							(mid 0.249642 0.249642)
							(end 0.2794 0.1778)
						)
						(arc
							(start 0.2794 -0.1778)
							(mid 0.249642 -0.249642)
							(end 0.1778 -0.2794)
						)
					)
					(width 0)
					(fill yes)
				)
			)
		)
		(pad "2" smd custom
			(at 0 0.4445 90)
			(size 0.1397 0.1397)
			(layers "F.Cu" "F.Mask" "F.Paste")
			(net "GND")
			(options
				(clearance outline)
				(anchor circle)
			)
			(primitives
				(gr_poly
					(pts
						(arc
							(start -0.1778 -0.2794)
							(mid -0.249642 -0.249642)
							(end -0.2794 -0.1778)
						)
						(arc
							(start -0.2794 0.1778)
							(mid -0.249642 0.249642)
							(end -0.1778 0.2794)
						)
						(arc
							(start 0.1778 0.2794)
							(mid 0.249642 0.249642)
							(end 0.2794 0.1778)
						)
						(arc
							(start 0.2794 -0.1778)
							(mid 0.249642 -0.249642)
							(end 0.1778 -0.2794)
						)
					)
					(width 0)
					(fill yes)
				)
			)
		)
	)
	(footprint ""
		(layer "F.Cu")
		(at 431.419 -33.02)
		(property "Reference" "Q174"
			(at 0 0 0)
			(layer "F.SilkS")
			(hide yes)
			(effects
				(font
					(size 1.27 1.27)
				)
			)
		)
		(property "Value" "AO4407AL-GP"
			(at -3.707384 -1.5367 0)
			(unlocked yes)
			(layer "F.Fab")
			(hide yes)
			(effects
				(font
					(size 1.016 1.016)
					(thickness 0.1524)
				)
			)
		)
		(property "Device Type" "SOIC8H69"
			(at -3.707384 -3.0607 0)
			(unlocked yes)
			(layer "F.Fab")
			(hide yes)
			(effects
				(font
					(size 1.016 1.016)
					(thickness 0.1524)
				)
			)
		)
		(duplicate_pad_numbers_are_jumpers no)
		(fp_line
			(start -2.7432 -1.4224)
			(end -2.7432 1.4224)
			(stroke
				(width 0.1524)
				(type default)
			)
			(layer "F.SilkS")
		)
		(fp_line
			(start -2.7432 1.4224)
			(end -2.6416 1.4224)
			(stroke
				(width 0.1524)
				(type default)
			)
			(layer "F.SilkS")
		)
		(fp_line
			(start -2.7432 1.4224)
			(end 2.1336 1.4224)
			(stroke
				(width 0.1524)
				(type default)
			)
			(layer "F.SilkS")
		)
		(fp_line
			(start -2.7178 -0.508)
			(end -2.1844 -0.0508)
			(stroke
				(width 0.1524)
				(type default)
			)
			(layer "F.SilkS")
		)
		(fp_line
			(start -2.6289 3.4417)
			(end -2.6289 1.4732)
			(stroke
				(width 0.381)
				(type default)
			)
			(layer "F.SilkS")
		)
		(fp_line
			(start -2.1844 -0.0508)
			(end -2.7178 0.508)
			(stroke
				(width 0.1524)
				(type default)
			)
			(layer "F.SilkS")
		)
		(fp_line
			(start 2.1336 -1.4224)
			(end -2.7432 -1.4224)
			(stroke
				(width 0.1524)
				(type default)
			)
			(layer "F.SilkS")
		)
		(fp_line
			(start 2.1336 1.4224)
			(end 2.1336 -1.4224)
			(stroke
				(width 0.1524)
				(type default)
			)
			(layer "F.SilkS")
		)
		(fp_poly
			(pts
				(xy -2.2098 -1.4224) (xy -2.2098 1.4224) (xy 2.2098 1.4224) (xy 2.2098 -1.4224)
			)
			(stroke
				(width 0)
				(type default)
			)
			(fill yes)
			(layer "F.SilkS")
		)
		(fp_rect
			(start -2.450084 2.999994)
			(end 2.450084 -2.999994)
			(stroke
				(width 0)
				(type default)
			)
			(fill no)
			(layer "F.CrtYd")
		)
		(fp_poly
			(pts
				(xy -2.8194 3.6322) (xy -2.8194 -3.6322) (xy 2.8194 -3.6322) (xy 2.8194 1.18364) (xy 2.450084 1.18364)
				(xy 2.450084 -2.999994) (xy -2.450084 -2.999994) (xy -2.450084 2.999994) (xy 2.450084 2.999994)
				(xy 2.450084 1.18618) (xy 2.8194 1.18618) (xy 2.8194 3.6322)
			)
			(stroke
				(width 0)
				(type default)
			)
			(fill no)
			(layer "F.CrtYd")
		)
		(fp_rect
			(start -2.8194 3.6322)
			(end 2.8194 -3.6322)
			(stroke
				(width 0)
				(type default)
			)
			(fill no)
			(layer "F.Fab")
		)
		(pad "1" smd rect
			(at -1.905 2.54)
			(size 0.635 1.651)
			(layers "F.Cu" "F.Mask" "F.Paste")
			(net "P12V_B")
		)
		(pad "2" smd rect
			(at -0.635 2.54)
			(size 0.635 1.651)
			(layers "F.Cu" "F.Mask" "F.Paste")
			(net "P12V_B")
		)
		(pad "3" smd rect
			(at 0.635 2.54)
			(size 0.635 1.651)
			(layers "F.Cu" "F.Mask" "F.Paste")
			(net "P12V_B")
		)
		(pad "4" smd rect
			(at 1.905 2.54)
			(size 0.635 1.651)
			(layers "F.Cu" "F.Mask" "F.Paste")
			(net "SW_HDD_N33")
		)
		(pad "5" smd rect
			(at 1.905 -2.54)
			(size 0.635 1.651)
			(layers "F.Cu" "F.Mask" "F.Paste")
			(net "P12V_HDD33")
		)
		(pad "6" smd rect
			(at 0.635 -2.54)
			(size 0.635 1.651)
			(layers "F.Cu" "F.Mask" "F.Paste")
			(net "P12V_HDD33")
		)
		(pad "7" smd rect
			(at -0.635 -2.54)
			(size 0.635 1.651)
			(layers "F.Cu" "F.Mask" "F.Paste")
			(net "P12V_HDD33")
		)
		(pad "8" smd rect
			(at -1.905 -2.54)
			(size 0.635 1.651)
			(layers "F.Cu" "F.Mask" "F.Paste")
			(net "P12V_HDD33")
		)
	)
)
